#ISCELL
  mstr_misc dns *
  *
#ISCELL
  mstr_symbols bom_note *
  *
#ISCELL
  mstr_symbols cad_note *
  *
#ISCELL
  mstr_symbols design_note *
  *
#ISCELL
  mstr_symbols intel_corp_bpage *
  *
#CELL
  mstr_discrete res *
  page137_i11
#ISCELL
  mstr_standard offpage *
  page137_i126
#CELL
  mstr_conn conn12_c73564003 *
  page137_i128
#ISCELL
  mstr_standard offpage *
  page137_i129
#CELL
  mstr_discrete res *
  page137_i13
#CELL
  mstr_discrete res *
  page137_i133
#ISCELL
  mstr_standard offpage *
  page137_i134
#ISCELL
  mstr_standard offpage *
  page137_i135
#ISCELL
  mstr_standard offpage *
  page137_i136
#CELL
  dev_discrete cap_a *
  page137_i14
#CELL
  mstr_discrete res *
  page137_i140
#ISCELL
  mstr_symbols gnd *
  page137_i141
#CELL
  mstr_discrete res *
  page137_i142
#ISCELL
  mstr_symbols p3v3_stby *
  page137_i143
#CELL
  mstr_discrete res *
  page137_i144
#ISCELL
  mstr_symbols gnd *
  page137_i145
#ISCELL
  mstr_symbols p3v3_stby *
  page137_i146
#ISCELL
  mstr_standard offpage *
  page137_i148
#CELL
  mstr_discrete res *
  page137_i149
#CELL
  mstr_discrete res *
  page137_i15
#ISCELL
  mstr_symbols gnd *
  page137_i16
#ISCELL
  mstr_standard offpage *
  page137_i17
#CELL
  mstr_discrete res *
  page137_i19
#CELL
  dev_discrete cap_a *
  page137_i20
#ISCELL
  mstr_symbols gnd *
  page137_i21
#CELL
  mstr_discrete res *
  page137_i67
#ISCELL
  mstr_symbols p3v3_stby *
  page137_i68
#CELL
  mstr_discrete res *
  page137_i69
#ISCELL
  mstr_symbols gnd *
  page137_i70
#ISCELL
  mstr_symbols p3v3_rtc_stby *
  page137_i78
#ISCELL
  mstr_symbols p3v3_rtc_stby *
  page137_i79
